(kicad_pcb
	(version 20260206)
	(generator "pcbnew")
	(generator_version "10.0")
	(general
		(thickness 1.6)
		(legacy_teardrops no)
	)
	(paper "A4")
	(title_block
		(title "04192023_DAF0TMB3IC0_F0TG_MB_C_brd_V02_OCP.brd")
		(comment 1 "Grand Teton / footprints 3452-3460 of 8354")
	)
	(layers
		(0 "F.Cu" signal "TOP")
		(4 "In1.Cu" signal "GND")
		(6 "In2.Cu" signal "IN1")
		(8 "In3.Cu" signal "GND1")
		(10 "In4.Cu" signal "IN2")
		(12 "In5.Cu" signal "GND2")
		(14 "In6.Cu" signal "IN3")
		(16 "In7.Cu" signal "GND3")
		(18 "In8.Cu" signal "VCC")
		(20 "In9.Cu" signal "VCC1")
		(22 "In10.Cu" signal "GND4")
		(24 "In11.Cu" signal "IN4")
		(26 "In12.Cu" signal "GND5")
		(28 "In13.Cu" signal "IN5")
		(30 "In14.Cu" signal "GND6")
		(32 "In15.Cu" signal "IN6")
		(34 "In16.Cu" signal "GND7")
		(2 "B.Cu" signal "BOTTOM")
		(9 "F.Adhes" user "F.Adhesive")
		(11 "B.Adhes" user "B.Adhesive")
		(13 "F.Paste" user "Package Geometry/Pastemask Top")
		(15 "B.Paste" user "Package Geometry/Pastemask Bottom")
		(5 "F.SilkS" user "Ref Des/Silkscreen Top")
		(7 "B.SilkS" user "Ref Des/Silkscreen Bottom")
		(1 "F.Mask" user "Board Geometry/Soldermask Top")
		(3 "B.Mask" user "Board Geometry/Soldermask Bottom")
		(17 "Dwgs.User" user "User.Drawings")
		(19 "Cmts.User" user "User.Comments")
		(21 "Eco1.User" user "User.Eco1")
		(23 "Eco2.User" user "User.Eco2")
		(25 "Edge.Cuts" user "Board Geometry/Outline")
		(27 "Margin" user)
		(31 "F.CrtYd" user "Package Geometry/Place Bound Top")
		(29 "B.CrtYd" user "Package Geometry/Place Bound Bottom")
		(35 "F.Fab" user "Ref Des/Assembly Top")
		(33 "B.Fab" user "Ref Des/Assembly Bottom")
	)
	(footprint ""
		(layer "F.Cu")
		(at 198.926196 -412.947612)
		(property "Reference" "ME4"
			(at 0 0 0)
			(layer "F.SilkS")
			(hide yes)
			(effects
				(font
					(size 1.27 1.27)
				)
			)
		)
		(property "Value" ""
			(at 0 0 0)
			(layer "F.Fab")
			(effects
				(font
					(size 1.27 1.27)
				)
			)
		)
		(duplicate_pad_numbers_are_jumpers no)
		(fp_line
			(start 0 -5.999988)
			(end 0 -4.475988)
			(stroke
				(width 0.1524)
				(type default)
			)
			(layer "F.SilkS")
		)
		(fp_line
			(start 0 -1.524)
			(end 0 0)
			(stroke
				(width 0.1524)
				(type default)
			)
			(layer "F.SilkS")
		)
		(fp_line
			(start 0 0)
			(end 1.524 0)
			(stroke
				(width 0.1524)
				(type default)
			)
			(layer "F.SilkS")
		)
		(fp_line
			(start 1.524 -5.999988)
			(end 0 -5.999988)
			(stroke
				(width 0.1524)
				(type default)
			)
			(layer "F.SilkS")
		)
		(fp_line
			(start 25.475946 -5.999988)
			(end 26.999946 -5.999988)
			(stroke
				(width 0.1524)
				(type default)
			)
			(layer "F.SilkS")
		)
		(fp_line
			(start 26.999946 -5.999988)
			(end 26.999946 -4.475988)
			(stroke
				(width 0.1524)
				(type default)
			)
			(layer "F.SilkS")
		)
		(fp_line
			(start 26.999946 -1.524)
			(end 26.999946 0)
			(stroke
				(width 0.1524)
				(type default)
			)
			(layer "F.SilkS")
		)
		(fp_line
			(start 26.999946 0)
			(end 25.475946 0)
			(stroke
				(width 0.1524)
				(type default)
			)
			(layer "F.SilkS")
		)
		(fp_text user "S/N"
			(at 0.2032 -4.59105 0)
			(unlocked yes)
			(layer "F.SilkS")
			(effects
				(font
					(size 1.905 1.4224)
					(thickness 0.1524)
				)
				(justify left)
			)
		)
	)
	(footprint ""
		(layer "F.Cu")
		(at 308.420516 -439.276744 -90)
		(property "Reference" "R4141"
			(at 0 0 270)
			(layer "F.SilkS")
			(hide yes)
			(effects
				(font
					(size 1.27 1.27)
				)
			)
		)
		(property "Value" ""
			(at 0 0 270)
			(layer "F.Fab")
			(effects
				(font
					(size 1.27 1.27)
				)
			)
		)
		(duplicate_pad_numbers_are_jumpers no)
		(fp_line
			(start -0.7874 0.4064)
			(end -0.7874 -0.4064)
			(stroke
				(width 0.1524)
				(type default)
			)
			(layer "F.SilkS")
		)
		(fp_line
			(start 0.7874 0.4064)
			(end -0.7874 0.4064)
			(stroke
				(width 0.1524)
				(type default)
			)
			(layer "F.SilkS")
		)
		(fp_line
			(start -0.7874 -0.4064)
			(end 0.7874 -0.4064)
			(stroke
				(width 0.1524)
				(type default)
			)
			(layer "F.SilkS")
		)
		(fp_line
			(start 0.7874 -0.4064)
			(end 0.7874 0.4064)
			(stroke
				(width 0.1524)
				(type default)
			)
			(layer "F.SilkS")
		)
		(fp_line
			(start -0.67945 0.3048)
			(end -0.67945 -0.305054)
			(stroke
				(width 0.1)
				(type default)
			)
			(layer "F.Fab")
		)
		(fp_line
			(start -0.12065 0.3048)
			(end -0.67945 0.3048)
			(stroke
				(width 0.1)
				(type default)
			)
			(layer "F.Fab")
		)
		(fp_line
			(start 0.120396 0.3048)
			(end 0.120396 0.2794)
			(stroke
				(width 0.1)
				(type default)
			)
			(layer "F.Fab")
		)
		(fp_line
			(start 0.67945 0.3048)
			(end 0.120396 0.3048)
			(stroke
				(width 0.1)
				(type default)
			)
			(layer "F.Fab")
		)
		(fp_line
			(start -0.12065 0.2794)
			(end -0.12065 0.3048)
			(stroke
				(width 0.1)
				(type default)
			)
			(layer "F.Fab")
		)
		(fp_line
			(start 0.120396 0.2794)
			(end -0.12065 0.2794)
			(stroke
				(width 0.1)
				(type default)
			)
			(layer "F.Fab")
		)
		(fp_line
			(start -0.12065 -0.2794)
			(end 0.12065 -0.2794)
			(stroke
				(width 0.1)
				(type default)
			)
			(layer "F.Fab")
		)
		(fp_line
			(start 0.12065 -0.2794)
			(end 0.12065 -0.3048)
			(stroke
				(width 0.1)
				(type default)
			)
			(layer "F.Fab")
		)
		(fp_line
			(start 0.12065 -0.3048)
			(end 0.67945 -0.3048)
			(stroke
				(width 0.1)
				(type default)
			)
			(layer "F.Fab")
		)
		(fp_line
			(start 0.67945 -0.3048)
			(end 0.67945 0.3048)
			(stroke
				(width 0.1)
				(type default)
			)
			(layer "F.Fab")
		)
		(fp_line
			(start -0.67945 -0.305054)
			(end -0.12065 -0.305054)
			(stroke
				(width 0.1)
				(type default)
			)
			(layer "F.Fab")
		)
		(fp_line
			(start -0.12065 -0.305054)
			(end -0.12065 -0.2794)
			(stroke
				(width 0.1)
				(type default)
			)
			(layer "F.Fab")
		)
		(pad "1" smd circle
			(at -0.40005 0 270)
			(size 0 0)
			(layers "F.Cu" "F.Mask" "F.Paste")
			(net "P3V3_AUX")
		)
		(pad "2" smd circle
			(at 0.40005 0 270)
			(size 0 0)
			(layers "F.Cu" "F.Mask" "F.Paste")
			(net "GPU_3V3IO_RSVD5_FFU_ISO")
		)
	)
	(footprint ""
		(layer "F.Cu")
		(at 420.658544 -423.744644 90)
		(property "Reference" "R682"
			(at 0 0 90)
			(layer "F.SilkS")
			(hide yes)
			(effects
				(font
					(size 1.27 1.27)
				)
			)
		)
		(property "Value" ""
			(at 0 0 90)
			(layer "F.Fab")
			(effects
				(font
					(size 1.27 1.27)
				)
			)
		)
		(duplicate_pad_numbers_are_jumpers no)
		(fp_line
			(start 0.32512 -0.175006)
			(end 0.32512 0.175006)
			(stroke
				(width 0.1)
				(type default)
			)
			(layer "F.Fab")
		)
		(fp_line
			(start -0.32512 -0.175006)
			(end 0.32512 -0.175006)
			(stroke
				(width 0.1)
				(type default)
			)
			(layer "F.Fab")
		)
		(fp_line
			(start 0.32512 0.175006)
			(end -0.32512 0.175006)
			(stroke
				(width 0.1)
				(type default)
			)
			(layer "F.Fab")
		)
		(fp_line
			(start -0.32512 0.175006)
			(end -0.32512 -0.175006)
			(stroke
				(width 0.1)
				(type default)
			)
			(layer "F.Fab")
		)
		(pad "1" smd rect
			(at -0.2667 0 90)
			(size 0.3048 0.381)
			(layers "F.Cu" "F.Mask" "F.Paste")
			(net "SMB_RT_CPU0_P2_ROM_R_SCL")
		)
		(pad "2" smd rect
			(at 0.2667 0 270)
			(size 0.3048 0.381)
			(layers "F.Cu" "F.Mask" "F.Paste")
			(net "SMB_RT_CPU0_P2_ROM_SCL")
		)
	)
	(footprint ""
		(layer "F.Cu")
		(at 70.382892 -47.049944)
		(property "Reference" "H31"
			(at -1.7272 -4.511548 0)
			(unlocked yes)
			(layer "B.SilkS")
			(effects
				(font
					(size 0.7874 0.5842)
					(thickness 0.1524)
				)
				(justify left mirror)
			)
		)
		(property "Value" ""
			(at 0 0 0)
			(layer "F.Fab")
			(effects
				(font
					(size 1.27 1.27)
				)
			)
		)
		(duplicate_pad_numbers_are_jumpers no)
		(pad "1" thru_hole circle
			(at 0 0)
			(size 4.5212 4.5212)
			(drill 3.81)
			(layers "*.Cu" "*.Mask")
			(remove_unused_layers no)
			(net "GND")
			(clearance -0.1016)
			(padstack
				(mode front_inner_back)
				(layer "Inner"
					(shape circle)
					(size 5.6134 5.6134)
					(clearance -0.6477)
				)
				(layer "B.Cu"
					(shape circle)
					(size 8.001 8.001)
					(clearance -1.8415)
				)
			)
		)
	)
	(footprint ""
		(layer "F.Cu")
		(at 34.870136 -389.439912)
		(property "Reference" "H5"
			(at -0.69088 -4.273804 0)
			(unlocked yes)
			(layer "F.SilkS")
			(effects
				(font
					(size 0.7874 0.5842)
					(thickness 0.1524)
				)
				(justify left)
			)
		)
		(property "Value" ""
			(at 0 0 0)
			(layer "F.Fab")
			(effects
				(font
					(size 1.27 1.27)
				)
			)
		)
		(duplicate_pad_numbers_are_jumpers no)
		(pad "1" thru_hole circle
			(at 0 0)
			(size 6.1976 6.1976)
			(drill 3.7338)
			(layers "*.Cu" "*.Mask")
			(remove_unused_layers no)
			(net "GND")
			(clearance -0.9779)
			(padstack
				(mode front_inner_back)
				(layer "Inner"
					(shape circle)
					(size 5.5372 5.5372)
					(clearance -0.6477)
				)
				(layer "B.Cu"
					(shape circle)
					(size 6.1976 6.1976)
					(clearance -0.9779)
				)
			)
		)
	)
	(footprint ""
		(layer "F.Cu")
		(at 97.239328 -339.681058 -90)
		(property "Reference" "PC428"
			(at 0 0 270)
			(layer "F.SilkS")
			(hide yes)
			(effects
				(font
					(size 1.27 1.27)
				)
			)
		)
		(property "Value" ""
			(at 0 0 270)
			(layer "F.Fab")
			(effects
				(font
					(size 1.27 1.27)
				)
			)
		)
		(duplicate_pad_numbers_are_jumpers no)
		(fp_line
			(start -0.7874 0.4064)
			(end -0.7874 -0.4064)
			(stroke
				(width 0.1524)
				(type default)
			)
			(layer "F.SilkS")
		)
		(fp_line
			(start 0.7874 0.4064)
			(end -0.7874 0.4064)
			(stroke
				(width 0.1524)
				(type default)
			)
			(layer "F.SilkS")
		)
		(fp_line
			(start -0.7874 -0.4064)
			(end 0.7874 -0.4064)
			(stroke
				(width 0.1524)
				(type default)
			)
			(layer "F.SilkS")
		)
		(fp_line
			(start 0.7874 -0.4064)
			(end 0.7874 0.4064)
			(stroke
				(width 0.1524)
				(type default)
			)
			(layer "F.SilkS")
		)
		(fp_line
			(start -0.67945 0.3048)
			(end -0.67945 -0.305054)
			(stroke
				(width 0.1)
				(type default)
			)
			(layer "F.Fab")
		)
		(fp_line
			(start -0.12065 0.3048)
			(end -0.67945 0.3048)
			(stroke
				(width 0.1)
				(type default)
			)
			(layer "F.Fab")
		)
		(fp_line
			(start 0.120396 0.3048)
			(end 0.120396 0.2794)
			(stroke
				(width 0.1)
				(type default)
			)
			(layer "F.Fab")
		)
		(fp_line
			(start 0.67945 0.3048)
			(end 0.120396 0.3048)
			(stroke
				(width 0.1)
				(type default)
			)
			(layer "F.Fab")
		)
		(fp_line
			(start -0.12065 0.2794)
			(end -0.12065 0.3048)
			(stroke
				(width 0.1)
				(type default)
			)
			(layer "F.Fab")
		)
		(fp_line
			(start 0.120396 0.2794)
			(end -0.12065 0.2794)
			(stroke
				(width 0.1)
				(type default)
			)
			(layer "F.Fab")
		)
		(fp_line
			(start -0.12065 -0.2794)
			(end 0.12065 -0.2794)
			(stroke
				(width 0.1)
				(type default)
			)
			(layer "F.Fab")
		)
		(fp_line
			(start 0.12065 -0.2794)
			(end 0.12065 -0.3048)
			(stroke
				(width 0.1)
				(type default)
			)
			(layer "F.Fab")
		)
		(fp_line
			(start 0.12065 -0.3048)
			(end 0.67945 -0.3048)
			(stroke
				(width 0.1)
				(type default)
			)
			(layer "F.Fab")
		)
		(fp_line
			(start 0.67945 -0.3048)
			(end 0.67945 0.3048)
			(stroke
				(width 0.1)
				(type default)
			)
			(layer "F.Fab")
		)
		(fp_line
			(start -0.67945 -0.305054)
			(end -0.12065 -0.305054)
			(stroke
				(width 0.1)
				(type default)
			)
			(layer "F.Fab")
		)
		(fp_line
			(start -0.12065 -0.305054)
			(end -0.12065 -0.2794)
			(stroke
				(width 0.1)
				(type default)
			)
			(layer "F.Fab")
		)
		(pad "1" smd circle
			(at -0.40005 0 270)
			(size 0 0)
			(layers "F.Cu" "F.Mask" "F.Paste")
			(net "SW_PVDDCR_CPU1_P1_BOOT5_R")
		)
		(pad "2" smd circle
			(at 0.40005 0 270)
			(size 0 0)
			(layers "F.Cu" "F.Mask" "F.Paste")
			(net "SW_PVDDCR_CPU1_P1_BOOTR5")
		)
	)
	(footprint ""
		(layer "F.Cu")
		(at 410.8196 -77.513434 90)
		(property "Reference" "C1862"
			(at 0 0 90)
			(layer "F.SilkS")
			(hide yes)
			(effects
				(font
					(size 1.27 1.27)
				)
			)
		)
		(property "Value" ""
			(at 0 0 90)
			(layer "F.Fab")
			(effects
				(font
					(size 1.27 1.27)
				)
			)
		)
		(duplicate_pad_numbers_are_jumpers no)
		(fp_line
			(start 0.7874 -0.4064)
			(end 0.7874 0.4064)
			(stroke
				(width 0.1524)
				(type default)
			)
			(layer "F.SilkS")
		)
		(fp_line
			(start -0.7874 -0.4064)
			(end 0.7874 -0.4064)
			(stroke
				(width 0.1524)
				(type default)
			)
			(layer "F.SilkS")
		)
		(fp_line
			(start 0.7874 0.4064)
			(end -0.7874 0.4064)
			(stroke
				(width 0.1524)
				(type default)
			)
			(layer "F.SilkS")
		)
		(fp_line
			(start -0.7874 0.4064)
			(end -0.7874 -0.4064)
			(stroke
				(width 0.1524)
				(type default)
			)
			(layer "F.SilkS")
		)
		(fp_line
			(start -0.12065 -0.305054)
			(end -0.12065 -0.2794)
			(stroke
				(width 0.1)
				(type default)
			)
			(layer "F.Fab")
		)
		(fp_line
			(start -0.67945 -0.305054)
			(end -0.12065 -0.305054)
			(stroke
				(width 0.1)
				(type default)
			)
			(layer "F.Fab")
		)
		(fp_line
			(start 0.67945 -0.3048)
			(end 0.67945 0.3048)
			(stroke
				(width 0.1)
				(type default)
			)
			(layer "F.Fab")
		)
		(fp_line
			(start 0.12065 -0.3048)
			(end 0.67945 -0.3048)
			(stroke
				(width 0.1)
				(type default)
			)
			(layer "F.Fab")
		)
		(fp_line
			(start 0.12065 -0.2794)
			(end 0.12065 -0.3048)
			(stroke
				(width 0.1)
				(type default)
			)
			(layer "F.Fab")
		)
		(fp_line
			(start -0.12065 -0.2794)
			(end 0.12065 -0.2794)
			(stroke
				(width 0.1)
				(type default)
			)
			(layer "F.Fab")
		)
		(fp_line
			(start 0.120396 0.2794)
			(end -0.12065 0.2794)
			(stroke
				(width 0.1)
				(type default)
			)
			(layer "F.Fab")
		)
		(fp_line
			(start -0.12065 0.2794)
			(end -0.12065 0.3048)
			(stroke
				(width 0.1)
				(type default)
			)
			(layer "F.Fab")
		)
		(fp_line
			(start 0.67945 0.3048)
			(end 0.120396 0.3048)
			(stroke
				(width 0.1)
				(type default)
			)
			(layer "F.Fab")
		)
		(fp_line
			(start 0.120396 0.3048)
			(end 0.120396 0.2794)
			(stroke
				(width 0.1)
				(type default)
			)
			(layer "F.Fab")
		)
		(fp_line
			(start -0.12065 0.3048)
			(end -0.67945 0.3048)
			(stroke
				(width 0.1)
				(type default)
			)
			(layer "F.Fab")
		)
		(fp_line
			(start -0.67945 0.3048)
			(end -0.67945 -0.305054)
			(stroke
				(width 0.1)
				(type default)
			)
			(layer "F.Fab")
		)
		(pad "1" smd circle
			(at -0.40005 0 90)
			(size 0 0)
			(layers "F.Cu" "F.Mask" "F.Paste")
			(net "P3V3_OCP_SFF")
		)
		(pad "2" smd circle
			(at 0.40005 0 90)
			(size 0 0)
			(layers "F.Cu" "F.Mask" "F.Paste")
			(net "GND")
		)
	)
	(footprint ""
		(layer "F.Cu")
		(at 82.324702 -373.03583 -90)
		(property "Reference" "C731"
			(at 0 0 270)
			(layer "F.SilkS")
			(hide yes)
			(effects
				(font
					(size 1.27 1.27)
				)
			)
		)
		(property "Value" ""
			(at 0 0 270)
			(layer "F.Fab")
			(effects
				(font
					(size 1.27 1.27)
				)
			)
		)
		(duplicate_pad_numbers_are_jumpers no)
		(fp_line
			(start -0.299974 0.150114)
			(end -0.299974 -0.150114)
			(stroke
				(width 0.1)
				(type default)
			)
			(layer "F.Fab")
		)
		(fp_line
			(start 0.299974 0.150114)
			(end -0.299974 0.150114)
			(stroke
				(width 0.1)
				(type default)
			)
			(layer "F.Fab")
		)
		(fp_line
			(start -0.299974 -0.150114)
			(end 0.299974 -0.150114)
			(stroke
				(width 0.1)
				(type default)
			)
			(layer "F.Fab")
		)
		(fp_line
			(start 0.299974 -0.150114)
			(end 0.299974 0.150114)
			(stroke
				(width 0.1)
				(type default)
			)
			(layer "F.Fab")
		)
		(pad "1" smd rect
			(at -0.2667 0 270)
			(size 0.3048 0.381)
			(layers "F.Cu" "F.Mask" "F.Paste")
			(net "P5E_CPU1_P1_TX_C_DP<5>")
		)
		(pad "2" smd rect
			(at 0.2667 0 270)
			(size 0.3048 0.381)
			(layers "F.Cu" "F.Mask" "F.Paste")
			(net "P5E_CPU1_P1_TX_DP<5>")
		)
	)
	(footprint ""
		(layer "F.Cu")
		(at 183.079898 -160.612074 90)
		(property "Reference" "R5021"
			(at 0 0 90)
			(layer "F.SilkS")
			(hide yes)
			(effects
				(font
					(size 1.27 1.27)
				)
			)
		)
		(property "Value" ""
			(at 0 0 90)
			(layer "F.Fab")
			(effects
				(font
					(size 1.27 1.27)
				)
			)
		)
		(duplicate_pad_numbers_are_jumpers no)
		(fp_line
			(start 0.7874 -0.4064)
			(end 0.7874 0.4064)
			(stroke
				(width 0.1524)
				(type default)
			)
			(layer "F.SilkS")
		)
		(fp_line
			(start -0.7874 -0.4064)
			(end 0.7874 -0.4064)
			(stroke
				(width 0.1524)
				(type default)
			)
			(layer "F.SilkS")
		)
		(fp_line
			(start 0.7874 0.4064)
			(end -0.7874 0.4064)
			(stroke
				(width 0.1524)
				(type default)
			)
			(layer "F.SilkS")
		)
		(fp_line
			(start -0.7874 0.4064)
			(end -0.7874 -0.4064)
			(stroke
				(width 0.1524)
				(type default)
			)
			(layer "F.SilkS")
		)
		(fp_line
			(start -0.12065 -0.305054)
			(end -0.12065 -0.2794)
			(stroke
				(width 0.1)
				(type default)
			)
			(layer "F.Fab")
		)
		(fp_line
			(start -0.67945 -0.305054)
			(end -0.12065 -0.305054)
			(stroke
				(width 0.1)
				(type default)
			)
			(layer "F.Fab")
		)
		(fp_line
			(start 0.67945 -0.3048)
			(end 0.67945 0.3048)
			(stroke
				(width 0.1)
				(type default)
			)
			(layer "F.Fab")
		)
		(fp_line
			(start 0.12065 -0.3048)
			(end 0.67945 -0.3048)
			(stroke
				(width 0.1)
				(type default)
			)
			(layer "F.Fab")
		)
		(fp_line
			(start 0.12065 -0.2794)
			(end 0.12065 -0.3048)
			(stroke
				(width 0.1)
				(type default)
			)
			(layer "F.Fab")
		)
		(fp_line
			(start -0.12065 -0.2794)
			(end 0.12065 -0.2794)
			(stroke
				(width 0.1)
				(type default)
			)
			(layer "F.Fab")
		)
		(fp_line
			(start 0.120396 0.2794)
			(end -0.12065 0.2794)
			(stroke
				(width 0.1)
				(type default)
			)
			(layer "F.Fab")
		)
		(fp_line
			(start -0.12065 0.2794)
			(end -0.12065 0.3048)
			(stroke
				(width 0.1)
				(type default)
			)
			(layer "F.Fab")
		)
		(fp_line
			(start 0.67945 0.3048)
			(end 0.120396 0.3048)
			(stroke
				(width 0.1)
				(type default)
			)
			(layer "F.Fab")
		)
		(fp_line
			(start 0.120396 0.3048)
			(end 0.120396 0.2794)
			(stroke
				(width 0.1)
				(type default)
			)
			(layer "F.Fab")
		)
		(fp_line
			(start -0.12065 0.3048)
			(end -0.67945 0.3048)
			(stroke
				(width 0.1)
				(type default)
			)
			(layer "F.Fab")
		)
		(fp_line
			(start -0.67945 0.3048)
			(end -0.67945 -0.305054)
			(stroke
				(width 0.1)
				(type default)
			)
			(layer "F.Fab")
		)
		(pad "1" smd circle
			(at -0.40005 0 90)
			(size 0 0)
			(layers "F.Cu" "F.Mask" "F.Paste")
			(net "PVDD11_S3_P1")
		)
		(pad "2" smd circle
			(at 0.40005 0 90)
			(size 0 0)
			(layers "F.Cu" "F.Mask" "F.Paste")
			(net "I3C_SCM_3_R_SDA")
		)
	)
)
